(kicad_pcb
	(version 20260206)
	(generator "pcbnew")
	(generator_version "10.0")
	(general
		(thickness 1.6)
		(legacy_teardrops no)
	)
	(paper "A4")
	(title_block
		(title "9052_F0T_PDB_Converter_Brick_F_V03_1208_1600_OCP.brd")
		(comment 1 "Grand Teton / footprints 553-558 of 578")
	)
	(layers
		(0 "F.Cu" signal "TOP")
		(4 "In1.Cu" signal "GND")
		(6 "In2.Cu" signal "IN1")
		(8 "In3.Cu" signal "GND1")
		(10 "In4.Cu" signal "VCC")
		(12 "In5.Cu" signal "VCC1")
		(14 "In6.Cu" signal "GND2")
		(16 "In7.Cu" signal "IN2")
		(18 "In8.Cu" signal "GND3")
		(2 "B.Cu" signal "BOTTOM")
		(9 "F.Adhes" user "F.Adhesive")
		(11 "B.Adhes" user "B.Adhesive")
		(13 "F.Paste" user "Package Geometry/Pastemask Top")
		(15 "B.Paste" user "Package Geometry/Pastemask Bottom")
		(5 "F.SilkS" user "Ref Des/Silkscreen Top")
		(7 "B.SilkS" user "Ref Des/Silkscreen Bottom")
		(1 "F.Mask" user "Board Geometry/Soldermask Top")
		(3 "B.Mask" user "Board Geometry/Soldermask Bottom")
		(17 "Dwgs.User" user "User.Drawings")
		(19 "Cmts.User" user "User.Comments")
		(21 "Eco1.User" user "User.Eco1")
		(23 "Eco2.User" user "User.Eco2")
		(25 "Edge.Cuts" user "Board Geometry/Outline")
		(27 "Margin" user)
		(31 "F.CrtYd" user "Package Geometry/Place Bound Top")
		(29 "B.CrtYd" user "Package Geometry/Place Bound Bottom")
		(35 "F.Fab" user "Ref Des/Assembly Top")
		(33 "B.Fab" user "Ref Des/Assembly Bottom")
	)
	(footprint ""
		(layer "B.Cu")
		(at 202.946 -88.011 180)
		(property "Reference" "R125"
			(at 0 0 0)
			(layer "B.SilkS")
			(hide yes)
			(effects
				(font
					(size 1.27 1.27)
				)
				(justify mirror)
			)
		)
		(property "Value" ""
			(at 0 0 0)
			(layer "B.Fab")
			(effects
				(font
					(size 1.27 1.27)
				)
				(justify mirror)
			)
		)
		(duplicate_pad_numbers_are_jumpers no)
		(fp_line
			(start 0.7874 0.4064)
			(end 0.7874 -0.4064)
			(stroke
				(width 0.1524)
				(type default)
			)
			(layer "B.SilkS")
		)
		(fp_line
			(start 0.7874 -0.4064)
			(end -0.7874 -0.4064)
			(stroke
				(width 0.1524)
				(type default)
			)
			(layer "B.SilkS")
		)
		(fp_line
			(start -0.7874 0.4064)
			(end 0.7874 0.4064)
			(stroke
				(width 0.1524)
				(type default)
			)
			(layer "B.SilkS")
		)
		(fp_line
			(start -0.7874 -0.4064)
			(end -0.7874 0.4064)
			(stroke
				(width 0.1524)
				(type default)
			)
			(layer "B.SilkS")
		)
		(fp_line
			(start 0.67945 0.3048)
			(end 0.67945 -0.305054)
			(stroke
				(width 0.1)
				(type default)
			)
			(layer "B.Fab")
		)
		(fp_line
			(start 0.67945 -0.305054)
			(end 0.12065 -0.305054)
			(stroke
				(width 0.1)
				(type default)
			)
			(layer "B.Fab")
		)
		(fp_line
			(start 0.12065 0.3048)
			(end 0.67945 0.3048)
			(stroke
				(width 0.1)
				(type default)
			)
			(layer "B.Fab")
		)
		(fp_line
			(start 0.12065 0.2794)
			(end 0.12065 0.3048)
			(stroke
				(width 0.1)
				(type default)
			)
			(layer "B.Fab")
		)
		(fp_line
			(start 0.12065 -0.2794)
			(end -0.12065 -0.2794)
			(stroke
				(width 0.1)
				(type default)
			)
			(layer "B.Fab")
		)
		(fp_line
			(start 0.12065 -0.305054)
			(end 0.12065 -0.2794)
			(stroke
				(width 0.1)
				(type default)
			)
			(layer "B.Fab")
		)
		(fp_line
			(start -0.120396 0.3048)
			(end -0.120396 0.2794)
			(stroke
				(width 0.1)
				(type default)
			)
			(layer "B.Fab")
		)
		(fp_line
			(start -0.120396 0.2794)
			(end 0.12065 0.2794)
			(stroke
				(width 0.1)
				(type default)
			)
			(layer "B.Fab")
		)
		(fp_line
			(start -0.12065 -0.2794)
			(end -0.12065 -0.3048)
			(stroke
				(width 0.1)
				(type default)
			)
			(layer "B.Fab")
		)
		(fp_line
			(start -0.12065 -0.3048)
			(end -0.67945 -0.3048)
			(stroke
				(width 0.1)
				(type default)
			)
			(layer "B.Fab")
		)
		(fp_line
			(start -0.67945 0.3048)
			(end -0.120396 0.3048)
			(stroke
				(width 0.1)
				(type default)
			)
			(layer "B.Fab")
		)
		(fp_line
			(start -0.67945 -0.3048)
			(end -0.67945 0.3048)
			(stroke
				(width 0.1)
				(type default)
			)
			(layer "B.Fab")
		)
		(pad "1" smd circle
			(at 0.40005 0)
			(size 0 0)
			(layers "B.Cu" "B.Mask" "B.Paste")
			(net "SMB_VPDB_MISC_SDA")
		)
		(pad "2" smd circle
			(at -0.40005 0)
			(size 0 0)
			(layers "B.Cu" "B.Mask" "B.Paste")
			(net "P3V3_AUX")
		)
	)
	(footprint ""
		(layer "B.Cu")
		(at 234.823 -91.313 90)
		(property "Reference" "C9"
			(at 0 0 90)
			(layer "B.SilkS")
			(hide yes)
			(effects
				(font
					(size 1.27 1.27)
				)
				(justify mirror)
			)
		)
		(property "Value" ""
			(at 0 0 90)
			(layer "B.Fab")
			(effects
				(font
					(size 1.27 1.27)
				)
				(justify mirror)
			)
		)
		(duplicate_pad_numbers_are_jumpers no)
		(fp_line
			(start 0.7874 -0.4064)
			(end -0.7874 -0.4064)
			(stroke
				(width 0.1524)
				(type default)
			)
			(layer "B.SilkS")
		)
		(fp_line
			(start -0.7874 -0.4064)
			(end -0.7874 0.4064)
			(stroke
				(width 0.1524)
				(type default)
			)
			(layer "B.SilkS")
		)
		(fp_line
			(start 0.7874 0.4064)
			(end 0.7874 -0.4064)
			(stroke
				(width 0.1524)
				(type default)
			)
			(layer "B.SilkS")
		)
		(fp_line
			(start -0.7874 0.4064)
			(end 0.7874 0.4064)
			(stroke
				(width 0.1524)
				(type default)
			)
			(layer "B.SilkS")
		)
		(fp_line
			(start 0.67945 -0.305054)
			(end 0.12065 -0.305054)
			(stroke
				(width 0.1)
				(type default)
			)
			(layer "B.Fab")
		)
		(fp_line
			(start 0.12065 -0.305054)
			(end 0.12065 -0.2794)
			(stroke
				(width 0.1)
				(type default)
			)
			(layer "B.Fab")
		)
		(fp_line
			(start -0.12065 -0.3048)
			(end -0.67945 -0.3048)
			(stroke
				(width 0.1)
				(type default)
			)
			(layer "B.Fab")
		)
		(fp_line
			(start -0.67945 -0.3048)
			(end -0.67945 0.3048)
			(stroke
				(width 0.1)
				(type default)
			)
			(layer "B.Fab")
		)
		(fp_line
			(start 0.12065 -0.2794)
			(end -0.12065 -0.2794)
			(stroke
				(width 0.1)
				(type default)
			)
			(layer "B.Fab")
		)
		(fp_line
			(start -0.12065 -0.2794)
			(end -0.12065 -0.3048)
			(stroke
				(width 0.1)
				(type default)
			)
			(layer "B.Fab")
		)
		(fp_line
			(start 0.12065 0.2794)
			(end 0.12065 0.3048)
			(stroke
				(width 0.1)
				(type default)
			)
			(layer "B.Fab")
		)
		(fp_line
			(start -0.120396 0.2794)
			(end 0.12065 0.2794)
			(stroke
				(width 0.1)
				(type default)
			)
			(layer "B.Fab")
		)
		(fp_line
			(start 0.67945 0.3048)
			(end 0.67945 -0.305054)
			(stroke
				(width 0.1)
				(type default)
			)
			(layer "B.Fab")
		)
		(fp_line
			(start 0.12065 0.3048)
			(end 0.67945 0.3048)
			(stroke
				(width 0.1)
				(type default)
			)
			(layer "B.Fab")
		)
		(fp_line
			(start -0.120396 0.3048)
			(end -0.120396 0.2794)
			(stroke
				(width 0.1)
				(type default)
			)
			(layer "B.Fab")
		)
		(fp_line
			(start -0.67945 0.3048)
			(end -0.120396 0.3048)
			(stroke
				(width 0.1)
				(type default)
			)
			(layer "B.Fab")
		)
		(pad "1" smd circle
			(at 0.40005 0 270)
			(size 0 0)
			(layers "B.Cu" "B.Mask" "B.Paste")
			(net "GND")
		)
		(pad "2" smd circle
			(at -0.40005 0 270)
			(size 0 0)
			(layers "B.Cu" "B.Mask" "B.Paste")
			(net "P3V3_AUX")
		)
	)
	(footprint ""
		(layer "B.Cu")
		(at 214.122 -91.059 -90)
		(property "Reference" "R32"
			(at 0 0 90)
			(layer "B.SilkS")
			(hide yes)
			(effects
				(font
					(size 1.27 1.27)
				)
				(justify mirror)
			)
		)
		(property "Value" ""
			(at 0 0 90)
			(layer "B.Fab")
			(effects
				(font
					(size 1.27 1.27)
				)
				(justify mirror)
			)
		)
		(duplicate_pad_numbers_are_jumpers no)
		(fp_line
			(start -0.7874 0.4064)
			(end 0.7874 0.4064)
			(stroke
				(width 0.1524)
				(type default)
			)
			(layer "B.SilkS")
		)
		(fp_line
			(start 0.7874 0.4064)
			(end 0.7874 -0.4064)
			(stroke
				(width 0.1524)
				(type default)
			)
			(layer "B.SilkS")
		)
		(fp_line
			(start -0.7874 -0.4064)
			(end -0.7874 0.4064)
			(stroke
				(width 0.1524)
				(type default)
			)
			(layer "B.SilkS")
		)
		(fp_line
			(start 0.7874 -0.4064)
			(end -0.7874 -0.4064)
			(stroke
				(width 0.1524)
				(type default)
			)
			(layer "B.SilkS")
		)
		(fp_line
			(start -0.67945 0.3048)
			(end -0.120396 0.3048)
			(stroke
				(width 0.1)
				(type default)
			)
			(layer "B.Fab")
		)
		(fp_line
			(start -0.120396 0.3048)
			(end -0.120396 0.2794)
			(stroke
				(width 0.1)
				(type default)
			)
			(layer "B.Fab")
		)
		(fp_line
			(start 0.12065 0.3048)
			(end 0.67945 0.3048)
			(stroke
				(width 0.1)
				(type default)
			)
			(layer "B.Fab")
		)
		(fp_line
			(start 0.67945 0.3048)
			(end 0.67945 -0.305054)
			(stroke
				(width 0.1)
				(type default)
			)
			(layer "B.Fab")
		)
		(fp_line
			(start -0.120396 0.2794)
			(end 0.12065 0.2794)
			(stroke
				(width 0.1)
				(type default)
			)
			(layer "B.Fab")
		)
		(fp_line
			(start 0.12065 0.2794)
			(end 0.12065 0.3048)
			(stroke
				(width 0.1)
				(type default)
			)
			(layer "B.Fab")
		)
		(fp_line
			(start -0.12065 -0.2794)
			(end -0.12065 -0.3048)
			(stroke
				(width 0.1)
				(type default)
			)
			(layer "B.Fab")
		)
		(fp_line
			(start 0.12065 -0.2794)
			(end -0.12065 -0.2794)
			(stroke
				(width 0.1)
				(type default)
			)
			(layer "B.Fab")
		)
		(fp_line
			(start -0.67945 -0.3048)
			(end -0.67945 0.3048)
			(stroke
				(width 0.1)
				(type default)
			)
			(layer "B.Fab")
		)
		(fp_line
			(start -0.12065 -0.3048)
			(end -0.67945 -0.3048)
			(stroke
				(width 0.1)
				(type default)
			)
			(layer "B.Fab")
		)
		(fp_line
			(start 0.12065 -0.305054)
			(end 0.12065 -0.2794)
			(stroke
				(width 0.1)
				(type default)
			)
			(layer "B.Fab")
		)
		(fp_line
			(start 0.67945 -0.305054)
			(end 0.12065 -0.305054)
			(stroke
				(width 0.1)
				(type default)
			)
			(layer "B.Fab")
		)
		(pad "1" smd circle
			(at 0.40005 0 90)
			(size 0 0)
			(layers "B.Cu" "B.Mask" "B.Paste")
			(net "FAN_PWR_EN_BUF_R")
		)
		(pad "2" smd circle
			(at -0.40005 0 90)
			(size 0 0)
			(layers "B.Cu" "B.Mask" "B.Paste")
			(net "FAN_PWR_EN_BUF")
		)
	)
	(footprint ""
		(layer "B.Cu")
		(at 238.555784 -80.10779)
		(property "Reference" "R7"
			(at 0 0 0)
			(layer "B.SilkS")
			(hide yes)
			(effects
				(font
					(size 1.27 1.27)
				)
				(justify mirror)
			)
		)
		(property "Value" ""
			(at 0 0 0)
			(layer "B.Fab")
			(effects
				(font
					(size 1.27 1.27)
				)
				(justify mirror)
			)
		)
		(duplicate_pad_numbers_are_jumpers no)
		(fp_line
			(start -0.7874 -0.4064)
			(end -0.7874 0.4064)
			(stroke
				(width 0.1524)
				(type default)
			)
			(layer "B.SilkS")
		)
		(fp_line
			(start -0.7874 0.4064)
			(end 0.7874 0.4064)
			(stroke
				(width 0.1524)
				(type default)
			)
			(layer "B.SilkS")
		)
		(fp_line
			(start 0.7874 -0.4064)
			(end -0.7874 -0.4064)
			(stroke
				(width 0.1524)
				(type default)
			)
			(layer "B.SilkS")
		)
		(fp_line
			(start 0.7874 0.4064)
			(end 0.7874 -0.4064)
			(stroke
				(width 0.1524)
				(type default)
			)
			(layer "B.SilkS")
		)
		(fp_line
			(start -0.67945 -0.3048)
			(end -0.67945 0.3048)
			(stroke
				(width 0.1)
				(type default)
			)
			(layer "B.Fab")
		)
		(fp_line
			(start -0.67945 0.3048)
			(end -0.120396 0.3048)
			(stroke
				(width 0.1)
				(type default)
			)
			(layer "B.Fab")
		)
		(fp_line
			(start -0.12065 -0.3048)
			(end -0.67945 -0.3048)
			(stroke
				(width 0.1)
				(type default)
			)
			(layer "B.Fab")
		)
		(fp_line
			(start -0.12065 -0.2794)
			(end -0.12065 -0.3048)
			(stroke
				(width 0.1)
				(type default)
			)
			(layer "B.Fab")
		)
		(fp_line
			(start -0.120396 0.2794)
			(end 0.12065 0.2794)
			(stroke
				(width 0.1)
				(type default)
			)
			(layer "B.Fab")
		)
		(fp_line
			(start -0.120396 0.3048)
			(end -0.120396 0.2794)
			(stroke
				(width 0.1)
				(type default)
			)
			(layer "B.Fab")
		)
		(fp_line
			(start 0.12065 -0.305054)
			(end 0.12065 -0.2794)
			(stroke
				(width 0.1)
				(type default)
			)
			(layer "B.Fab")
		)
		(fp_line
			(start 0.12065 -0.2794)
			(end -0.12065 -0.2794)
			(stroke
				(width 0.1)
				(type default)
			)
			(layer "B.Fab")
		)
		(fp_line
			(start 0.12065 0.2794)
			(end 0.12065 0.3048)
			(stroke
				(width 0.1)
				(type default)
			)
			(layer "B.Fab")
		)
		(fp_line
			(start 0.12065 0.3048)
			(end 0.67945 0.3048)
			(stroke
				(width 0.1)
				(type default)
			)
			(layer "B.Fab")
		)
		(fp_line
			(start 0.67945 -0.305054)
			(end 0.12065 -0.305054)
			(stroke
				(width 0.1)
				(type default)
			)
			(layer "B.Fab")
		)
		(fp_line
			(start 0.67945 0.3048)
			(end 0.67945 -0.305054)
			(stroke
				(width 0.1)
				(type default)
			)
			(layer "B.Fab")
		)
		(pad "1" smd circle
			(at 0.40005 0 180)
			(size 0 0)
			(layers "B.Cu" "B.Mask" "B.Paste")
			(net "SMB_MB_PDB_SDA")
		)
		(pad "2" smd circle
			(at -0.40005 0 180)
			(size 0 0)
			(layers "B.Cu" "B.Mask" "B.Paste")
			(net "SMB_PDB_MISC_SDA_R")
		)
	)
	(footprint ""
		(layer "B.Cu")
		(at 280.543 -35.941 90)
		(property "Reference" "R5931"
			(at 0 0 90)
			(layer "B.SilkS")
			(hide yes)
			(effects
				(font
					(size 1.27 1.27)
				)
				(justify mirror)
			)
		)
		(property "Value" ""
			(at 0 0 90)
			(layer "B.Fab")
			(effects
				(font
					(size 1.27 1.27)
				)
				(justify mirror)
			)
		)
		(duplicate_pad_numbers_are_jumpers no)
		(fp_line
			(start 0.7874 -0.4064)
			(end -0.7874 -0.4064)
			(stroke
				(width 0.1524)
				(type default)
			)
			(layer "B.SilkS")
		)
		(fp_line
			(start -0.7874 -0.4064)
			(end -0.7874 0.4064)
			(stroke
				(width 0.1524)
				(type default)
			)
			(layer "B.SilkS")
		)
		(fp_line
			(start 0.7874 0.4064)
			(end 0.7874 -0.4064)
			(stroke
				(width 0.1524)
				(type default)
			)
			(layer "B.SilkS")
		)
		(fp_line
			(start -0.7874 0.4064)
			(end 0.7874 0.4064)
			(stroke
				(width 0.1524)
				(type default)
			)
			(layer "B.SilkS")
		)
		(fp_line
			(start 0.67945 -0.305054)
			(end 0.12065 -0.305054)
			(stroke
				(width 0.1)
				(type default)
			)
			(layer "B.Fab")
		)
		(fp_line
			(start 0.12065 -0.305054)
			(end 0.12065 -0.2794)
			(stroke
				(width 0.1)
				(type default)
			)
			(layer "B.Fab")
		)
		(fp_line
			(start -0.12065 -0.3048)
			(end -0.67945 -0.3048)
			(stroke
				(width 0.1)
				(type default)
			)
			(layer "B.Fab")
		)
		(fp_line
			(start -0.67945 -0.3048)
			(end -0.67945 0.3048)
			(stroke
				(width 0.1)
				(type default)
			)
			(layer "B.Fab")
		)
		(fp_line
			(start 0.12065 -0.2794)
			(end -0.12065 -0.2794)
			(stroke
				(width 0.1)
				(type default)
			)
			(layer "B.Fab")
		)
		(fp_line
			(start -0.12065 -0.2794)
			(end -0.12065 -0.3048)
			(stroke
				(width 0.1)
				(type default)
			)
			(layer "B.Fab")
		)
		(fp_line
			(start 0.12065 0.2794)
			(end 0.12065 0.3048)
			(stroke
				(width 0.1)
				(type default)
			)
			(layer "B.Fab")
		)
		(fp_line
			(start -0.120396 0.2794)
			(end 0.12065 0.2794)
			(stroke
				(width 0.1)
				(type default)
			)
			(layer "B.Fab")
		)
		(fp_line
			(start 0.67945 0.3048)
			(end 0.67945 -0.305054)
			(stroke
				(width 0.1)
				(type default)
			)
			(layer "B.Fab")
		)
		(fp_line
			(start 0.12065 0.3048)
			(end 0.67945 0.3048)
			(stroke
				(width 0.1)
				(type default)
			)
			(layer "B.Fab")
		)
		(fp_line
			(start -0.120396 0.3048)
			(end -0.120396 0.2794)
			(stroke
				(width 0.1)
				(type default)
			)
			(layer "B.Fab")
		)
		(fp_line
			(start -0.67945 0.3048)
			(end -0.120396 0.3048)
			(stroke
				(width 0.1)
				(type default)
			)
			(layer "B.Fab")
		)
		(pad "1" smd circle
			(at 0.40005 0 270)
			(size 0 0)
			(layers "B.Cu" "B.Mask" "B.Paste")
			(net "P52V_HS1_EN_DELAY_N")
		)
		(pad "2" smd circle
			(at -0.40005 0 270)
			(size 0 0)
			(layers "B.Cu" "B.Mask" "B.Paste")
			(net "GND")
		)
	)
	(footprint ""
		(layer "B.Cu")
		(at 98.806 -78.613)
		(property "Reference" "R174"
			(at 0 0 0)
			(layer "B.SilkS")
			(hide yes)
			(effects
				(font
					(size 1.27 1.27)
				)
				(justify mirror)
			)
		)
		(property "Value" ""
			(at 0 0 0)
			(layer "B.Fab")
			(effects
				(font
					(size 1.27 1.27)
				)
				(justify mirror)
			)
		)
		(duplicate_pad_numbers_are_jumpers no)
		(fp_line
			(start -0.7874 -0.4064)
			(end -0.7874 0.4064)
			(stroke
				(width 0.1524)
				(type default)
			)
			(layer "B.SilkS")
		)
		(fp_line
			(start -0.7874 0.4064)
			(end 0.7874 0.4064)
			(stroke
				(width 0.1524)
				(type default)
			)
			(layer "B.SilkS")
		)
		(fp_line
			(start 0.7874 -0.4064)
			(end -0.7874 -0.4064)
			(stroke
				(width 0.1524)
				(type default)
			)
			(layer "B.SilkS")
		)
		(fp_line
			(start 0.7874 0.4064)
			(end 0.7874 -0.4064)
			(stroke
				(width 0.1524)
				(type default)
			)
			(layer "B.SilkS")
		)
		(fp_line
			(start -0.67945 -0.3048)
			(end -0.67945 0.3048)
			(stroke
				(width 0.1)
				(type default)
			)
			(layer "B.Fab")
		)
		(fp_line
			(start -0.67945 0.3048)
			(end -0.120396 0.3048)
			(stroke
				(width 0.1)
				(type default)
			)
			(layer "B.Fab")
		)
		(fp_line
			(start -0.12065 -0.3048)
			(end -0.67945 -0.3048)
			(stroke
				(width 0.1)
				(type default)
			)
			(layer "B.Fab")
		)
		(fp_line
			(start -0.12065 -0.2794)
			(end -0.12065 -0.3048)
			(stroke
				(width 0.1)
				(type default)
			)
			(layer "B.Fab")
		)
		(fp_line
			(start -0.120396 0.2794)
			(end 0.12065 0.2794)
			(stroke
				(width 0.1)
				(type default)
			)
			(layer "B.Fab")
		)
		(fp_line
			(start -0.120396 0.3048)
			(end -0.120396 0.2794)
			(stroke
				(width 0.1)
				(type default)
			)
			(layer "B.Fab")
		)
		(fp_line
			(start 0.12065 -0.305054)
			(end 0.12065 -0.2794)
			(stroke
				(width 0.1)
				(type default)
			)
			(layer "B.Fab")
		)
		(fp_line
			(start 0.12065 -0.2794)
			(end -0.12065 -0.2794)
			(stroke
				(width 0.1)
				(type default)
			)
			(layer "B.Fab")
		)
		(fp_line
			(start 0.12065 0.2794)
			(end 0.12065 0.3048)
			(stroke
				(width 0.1)
				(type default)
			)
			(layer "B.Fab")
		)
		(fp_line
			(start 0.12065 0.3048)
			(end 0.67945 0.3048)
			(stroke
				(width 0.1)
				(type default)
			)
			(layer "B.Fab")
		)
		(fp_line
			(start 0.67945 -0.305054)
			(end 0.12065 -0.305054)
			(stroke
				(width 0.1)
				(type default)
			)
			(layer "B.Fab")
		)
		(fp_line
			(start 0.67945 0.3048)
			(end 0.67945 -0.305054)
			(stroke
				(width 0.1)
				(type default)
			)
			(layer "B.Fab")
		)
		(pad "1" smd circle
			(at 0.40005 0 180)
			(size 0 0)
			(layers "B.Cu" "B.Mask" "B.Paste")
			(net "P3V3_AUX")
		)
		(pad "2" smd circle
			(at -0.40005 0 180)
			(size 0 0)
			(layers "B.Cu" "B.Mask" "B.Paste")
			(net "SMB_P52V_VPDB_SDA")
		)
	)
)
